(kicad_pcb
	(version 20260206)
	(generator "pcbnew")
	(generator_version "10.0")
	(general
		(thickness 1.6)
		(legacy_teardrops no)
	)
	(paper "A4")
	(title_block
		(title "04192023_DAF0TMB3IC0_F0TG_MB_C_brd_V02_OCP.brd")
		(comment 1 "Grand Teton / footprint 3955 of 8354 (U25), pads 2217-2331 of 6102")
	)
	(layers
		(0 "F.Cu" signal "TOP")
		(4 "In1.Cu" signal "GND")
		(6 "In2.Cu" signal "IN1")
		(8 "In3.Cu" signal "GND1")
		(10 "In4.Cu" signal "IN2")
		(12 "In5.Cu" signal "GND2")
		(14 "In6.Cu" signal "IN3")
		(16 "In7.Cu" signal "GND3")
		(18 "In8.Cu" signal "VCC")
		(20 "In9.Cu" signal "VCC1")
		(22 "In10.Cu" signal "GND4")
		(24 "In11.Cu" signal "IN4")
		(26 "In12.Cu" signal "GND5")
		(28 "In13.Cu" signal "IN5")
		(30 "In14.Cu" signal "GND6")
		(32 "In15.Cu" signal "IN6")
		(34 "In16.Cu" signal "GND7")
		(2 "B.Cu" signal "BOTTOM")
		(9 "F.Adhes" user "F.Adhesive")
		(11 "B.Adhes" user "B.Adhesive")
		(13 "F.Paste" user "Package Geometry/Pastemask Top")
		(15 "B.Paste" user "Package Geometry/Pastemask Bottom")
		(5 "F.SilkS" user "Ref Des/Silkscreen Top")
		(7 "B.SilkS" user "Ref Des/Silkscreen Bottom")
		(1 "F.Mask" user "Board Geometry/Soldermask Top")
		(3 "B.Mask" user "Board Geometry/Soldermask Bottom")
		(17 "Dwgs.User" user "User.Drawings")
		(19 "Cmts.User" user "User.Comments")
		(21 "Eco1.User" user "User.Eco1")
		(23 "Eco2.User" user "User.Eco2")
		(25 "Edge.Cuts" user "Board Geometry/Outline")
		(27 "Margin" user)
		(31 "F.CrtYd" user "Package Geometry/Place Bound Top")
		(29 "B.CrtYd" user "Package Geometry/Place Bound Bottom")
		(35 "F.Fab" user "Ref Des/Assembly Top")
		(33 "B.Fab" user "Ref Des/Assembly Bottom")
	)
	(footprint ""
		(layer "F.Cu")
		(at 359.867962 -258.880102 180)
		(property "Reference" "U25"
			(at -45.78477 -62.086744 0)
			(unlocked yes)
			(layer "F.SilkS")
			(effects
				(font
					(size 0.7874 0.5842)
					(thickness 0.1524)
				)
			)
		)
		(property "Value" ""
			(at 0 0 180)
			(layer "F.Fab")
			(effects
				(font
					(size 1.27 1.27)
				)
			)
		)
		(duplicate_pad_numbers_are_jumpers no)
		(pad "BN60" smd circle
			(at 20.059904 7.649972 180)
			(size 0.450088 0.450088)
			(layers "F.Cu" "F.Mask" "F.Paste")
			(net "M_D_CPU0_SB_CS_N<1>")
		)
		(pad "BN61" smd circle
			(at 20.999958 7.649972 180)
			(size 0.450088 0.450088)
			(layers "F.Cu" "F.Mask" "F.Paste")
			(net "GND")
		)
		(pad "BN62" smd circle
			(at 21.940012 7.649972 180)
			(size 0.450088 0.450088)
			(layers "F.Cu" "F.Mask" "F.Paste")
			(net "M_B_CPU0_SA_RSP<0>")
		)
		(pad "BN63" smd circle
			(at 22.880066 7.649972 180)
			(size 0.450088 0.450088)
			(layers "F.Cu" "F.Mask" "F.Paste")
			(net "GND")
		)
		(pad "BN64" smd circle
			(at 23.82012 7.649972 180)
			(size 0.450088 0.450088)
			(layers "F.Cu" "F.Mask" "F.Paste")
			(net "M_B_CPU0_SB_CS_N<1>")
		)
		(pad "BN65" smd circle
			(at 24.75992 7.649972 180)
			(size 0.450088 0.450088)
			(layers "F.Cu" "F.Mask" "F.Paste")
			(net "GND")
		)
		(pad "BN66" smd circle
			(at 25.699974 7.649972 180)
			(size 0.450088 0.450088)
			(layers "F.Cu" "F.Mask" "F.Paste")
			(net "M_F_CPU0_SA_RSP<0>")
		)
		(pad "BN67" smd circle
			(at 26.640028 7.649972 180)
			(size 0.450088 0.450088)
			(layers "F.Cu" "F.Mask" "F.Paste")
			(net "M_F_CPU0_SB_CS_N<1>")
		)
		(pad "BN68" smd circle
			(at 27.580082 7.649972 180)
			(size 0.450088 0.450088)
			(layers "F.Cu" "F.Mask" "F.Paste")
			(net "GND")
		)
		(pad "BN69" smd circle
			(at 28.519882 7.649972 180)
			(size 0.450088 0.450088)
			(layers "F.Cu" "F.Mask" "F.Paste")
			(net "M_E_CPU0_SA_RSP<0>")
		)
		(pad "BN70" smd circle
			(at 29.459936 7.649972 180)
			(size 0.450088 0.450088)
			(layers "F.Cu" "F.Mask" "F.Paste")
			(net "GND")
		)
		(pad "BN71" smd circle
			(at 30.39999 7.649972 180)
			(size 0.450088 0.450088)
			(layers "F.Cu" "F.Mask" "F.Paste")
			(net "M_E_CPU0_SB_CS_N<1>")
		)
		(pad "BN72" smd circle
			(at 31.340044 7.649972 180)
			(size 0.450088 0.450088)
			(layers "F.Cu" "F.Mask" "F.Paste")
			(net "GND")
		)
		(pad "BN73" smd circle
			(at 32.280098 7.649972 180)
			(size 0.450088 0.450088)
			(layers "F.Cu" "F.Mask" "F.Paste")
			(net "M_A_CPU0_SA_RSP<0>")
		)
		(pad "BN74" smd circle
			(at 33.219898 7.649972 180)
			(size 0.450088 0.450088)
			(layers "F.Cu" "F.Mask" "F.Paste")
			(net "M_A_CPU0_SB_CS_N<1>")
		)
		(pad "BN75" smd circle
			(at 34.159952 7.649972 180)
			(size 0.450088 0.450088)
			(layers "F.Cu" "F.Mask" "F.Paste")
			(net "GND")
		)
		(pad "BP2" smd circle
			(at -33.990026 8.459978 180)
			(size 0.450088 0.450088)
			(layers "F.Cu" "F.Mask" "F.Paste")
			(net "M_G_CPU0_SB_RSP<0>")
		)
		(pad "BP3" smd circle
			(at -33.049972 8.459978 180)
			(size 0.450088 0.450088)
			(layers "F.Cu" "F.Mask" "F.Paste")
			(net "GND")
		)
		(pad "BP4" smd circle
			(at -32.109918 8.459978 180)
			(size 0.450088 0.450088)
			(layers "F.Cu" "F.Mask" "F.Paste")
			(net "Net_1839")
		)
		(pad "BP5" smd circle
			(at -31.170118 8.459978 180)
			(size 0.450088 0.450088)
			(layers "F.Cu" "F.Mask" "F.Paste")
			(net "GND")
		)
		(pad "BP6" smd circle
			(at -30.230064 8.459978 180)
			(size 0.450088 0.450088)
			(layers "F.Cu" "F.Mask" "F.Paste")
			(net "M_K_CPU0_SB_RSP<0>")
		)
		(pad "BP7" smd circle
			(at -29.29001 8.459978 180)
			(size 0.450088 0.450088)
			(layers "F.Cu" "F.Mask" "F.Paste")
			(net "Net_1968")
		)
		(pad "BP8" smd circle
			(at -28.349956 8.459978 180)
			(size 0.450088 0.450088)
			(layers "F.Cu" "F.Mask" "F.Paste")
			(net "GND")
		)
		(pad "BP9" smd circle
			(at -27.409902 8.459978 180)
			(size 0.450088 0.450088)
			(layers "F.Cu" "F.Mask" "F.Paste")
			(net "M_L_CPU0_SB_RSP<0>")
		)
		(pad "BP10" smd circle
			(at -26.470102 8.459978 180)
			(size 0.450088 0.450088)
			(layers "F.Cu" "F.Mask" "F.Paste")
			(net "GND")
		)
		(pad "BP11" smd circle
			(at -25.530048 8.459978 180)
			(size 0.450088 0.450088)
			(layers "F.Cu" "F.Mask" "F.Paste")
			(net "Net_1960")
		)
		(pad "BP12" smd circle
			(at -24.589994 8.459978 180)
			(size 0.450088 0.450088)
			(layers "F.Cu" "F.Mask" "F.Paste")
			(net "GND")
		)
		(pad "BP13" smd circle
			(at -23.64994 8.459978 180)
			(size 0.450088 0.450088)
			(layers "F.Cu" "F.Mask" "F.Paste")
			(net "M_H_CPU0_SB_RSP<0>")
		)
		(pad "BP14" smd circle
			(at -22.709886 8.459978 180)
			(size 0.450088 0.450088)
			(layers "F.Cu" "F.Mask" "F.Paste")
			(net "Net_1847")
		)
		(pad "BP15" smd circle
			(at -21.770086 8.459978 180)
			(size 0.450088 0.450088)
			(layers "F.Cu" "F.Mask" "F.Paste")
			(net "GND")
		)
		(pad "BP16" smd circle
			(at -20.830032 8.459978 180)
			(size 0.450088 0.450088)
			(layers "F.Cu" "F.Mask" "F.Paste")
			(net "M_J_CPU0_SB_RSP<0>")
		)
		(pad "BP17" smd circle
			(at -19.889978 8.459978 180)
			(size 0.450088 0.450088)
			(layers "F.Cu" "F.Mask" "F.Paste")
			(net "GND")
		)
		(pad "BP18" smd circle
			(at -18.949924 8.459978 180)
			(size 0.450088 0.450088)
			(layers "F.Cu" "F.Mask" "F.Paste")
			(net "Net_1863")
		)
		(pad "BP19" smd circle
			(at -18.010124 8.459978 180)
			(size 0.450088 0.450088)
			(layers "F.Cu" "F.Mask" "F.Paste")
			(net "GND")
		)
		(pad "BP20" smd circle
			(at -17.07007 8.459978 180)
			(size 0.450088 0.450088)
			(layers "F.Cu" "F.Mask" "F.Paste")
			(net "M_I_CPU0_SB_RSP<0>")
		)
		(pad "BP21" smd circle
			(at -16.130016 8.459978 180)
			(size 0.450088 0.450088)
			(layers "F.Cu" "F.Mask" "F.Paste")
			(net "Net_1855")
		)
		(pad "BP22" smd circle
			(at -15.189962 8.459978 180)
			(size 0.450088 0.450088)
			(layers "F.Cu" "F.Mask" "F.Paste")
			(net "PVDD11_S3_P0")
		)
		(pad "BP23" smd circle
			(at -14.249908 8.459978 180)
			(size 0.450088 0.450088)
			(layers "F.Cu" "F.Mask" "F.Paste")
			(net "GND")
		)
		(pad "BP24" smd circle
			(at -13.310108 8.459978 180)
			(size 0.450088 0.450088)
			(layers "F.Cu" "F.Mask" "F.Paste")
			(net "PVDDCR_CPU1_P0")
		)
		(pad "BP25" smd circle
			(at -12.370054 8.459978 180)
			(size 0.450088 0.450088)
			(layers "F.Cu" "F.Mask" "F.Paste")
			(net "GND")
		)
		(pad "BP26" smd circle
			(at -11.43 8.459978 180)
			(size 0.450088 0.450088)
			(layers "F.Cu" "F.Mask" "F.Paste")
			(net "PVDDCR_CPU1_P0")
		)
		(pad "BP27" smd circle
			(at -10.489946 8.459978 180)
			(size 0.450088 0.450088)
			(layers "F.Cu" "F.Mask" "F.Paste")
			(net "GND")
		)
		(pad "BP28" smd circle
			(at -9.549892 8.459978 180)
			(size 0.450088 0.450088)
			(layers "F.Cu" "F.Mask" "F.Paste")
			(net "PVDDCR_CPU1_P0")
		)
		(pad "BP29" smd circle
			(at -8.610092 8.459978 180)
			(size 0.450088 0.450088)
			(layers "F.Cu" "F.Mask" "F.Paste")
			(net "GND")
		)
		(pad "BP30" smd circle
			(at -7.670038 8.459978 180)
			(size 0.450088 0.450088)
			(layers "F.Cu" "F.Mask" "F.Paste")
			(net "PVDDCR_CPU1_P0")
		)
		(pad "BP31" smd circle
			(at -6.729984 8.459978 180)
			(size 0.450088 0.450088)
			(layers "F.Cu" "F.Mask" "F.Paste")
			(net "GND")
		)
		(pad "BP32" smd circle
			(at -5.78993 8.459978 180)
			(size 0.450088 0.450088)
			(layers "F.Cu" "F.Mask" "F.Paste")
			(net "PVDDCR_CPU1_P0")
		)
		(pad "BP33" smd circle
			(at -4.849876 8.459978 180)
			(size 0.450088 0.450088)
			(layers "F.Cu" "F.Mask" "F.Paste")
			(net "GND")
		)
		(pad "BP34" smd circle
			(at -3.910076 8.459978 180)
			(size 0.450088 0.450088)
			(layers "F.Cu" "F.Mask" "F.Paste")
			(net "PVDDCR_CPU1_P0")
		)
		(pad "BP35" smd circle
			(at -2.970022 8.459978 180)
			(size 0.450088 0.450088)
			(layers "F.Cu" "F.Mask" "F.Paste")
			(net "GND")
		)
		(pad "BP36" smd circle
			(at -2.029968 8.459978 180)
			(size 0.450088 0.450088)
			(layers "F.Cu" "F.Mask" "F.Paste")
			(net "PVDDCR_CPU1_P0")
		)
		(pad "BP37" smd circle
			(at -1.089914 8.459978 180)
			(size 0.450088 0.450088)
			(layers "F.Cu" "F.Mask" "F.Paste")
			(net "GND")
		)
		(pad "BP39" smd circle
			(at 0.78994 8.459978 180)
			(size 0.450088 0.450088)
			(layers "F.Cu" "F.Mask" "F.Paste")
			(net "PVDDCR_CPU1_P0")
		)
		(pad "BP40" smd circle
			(at 1.729994 8.459978 180)
			(size 0.450088 0.450088)
			(layers "F.Cu" "F.Mask" "F.Paste")
			(net "GND")
		)
		(pad "BP41" smd circle
			(at 2.670048 8.459978 180)
			(size 0.450088 0.450088)
			(layers "F.Cu" "F.Mask" "F.Paste")
			(net "PVDDCR_CPU1_P0")
		)
		(pad "BP42" smd circle
			(at 3.610102 8.459978 180)
			(size 0.450088 0.450088)
			(layers "F.Cu" "F.Mask" "F.Paste")
			(net "GND")
		)
		(pad "BP43" smd circle
			(at 4.549902 8.459978 180)
			(size 0.450088 0.450088)
			(layers "F.Cu" "F.Mask" "F.Paste")
			(net "PVDDCR_CPU1_P0")
		)
		(pad "BP44" smd circle
			(at 5.489956 8.459978 180)
			(size 0.450088 0.450088)
			(layers "F.Cu" "F.Mask" "F.Paste")
			(net "GND")
		)
		(pad "BP45" smd circle
			(at 6.43001 8.459978 180)
			(size 0.450088 0.450088)
			(layers "F.Cu" "F.Mask" "F.Paste")
			(net "PVDDCR_CPU1_P0")
		)
		(pad "BP46" smd circle
			(at 7.370064 8.459978 180)
			(size 0.450088 0.450088)
			(layers "F.Cu" "F.Mask" "F.Paste")
			(net "GND")
		)
		(pad "BP47" smd circle
			(at 8.310118 8.459978 180)
			(size 0.450088 0.450088)
			(layers "F.Cu" "F.Mask" "F.Paste")
			(net "PVDDCR_CPU1_P0")
		)
		(pad "BP48" smd circle
			(at 9.249918 8.459978 180)
			(size 0.450088 0.450088)
			(layers "F.Cu" "F.Mask" "F.Paste")
			(net "GND")
		)
		(pad "BP49" smd circle
			(at 10.189972 8.459978 180)
			(size 0.450088 0.450088)
			(layers "F.Cu" "F.Mask" "F.Paste")
			(net "PVDDCR_CPU1_P0")
		)
		(pad "BP50" smd circle
			(at 11.130026 8.459978 180)
			(size 0.450088 0.450088)
			(layers "F.Cu" "F.Mask" "F.Paste")
			(net "GND")
		)
		(pad "BP51" smd circle
			(at 12.07008 8.459978 180)
			(size 0.450088 0.450088)
			(layers "F.Cu" "F.Mask" "F.Paste")
			(net "PVDD_33_S5")
		)
		(pad "BP52" smd circle
			(at 13.00988 8.459978 180)
			(size 0.450088 0.450088)
			(layers "F.Cu" "F.Mask" "F.Paste")
			(net "GND")
		)
		(pad "BP53" smd circle
			(at 13.949934 8.459978 180)
			(size 0.450088 0.450088)
			(layers "F.Cu" "F.Mask" "F.Paste")
			(net "TP_VSENSE_PVDD33_S5_P0")
		)
		(pad "BP54" smd circle
			(at 14.889988 8.459978 180)
			(size 0.450088 0.450088)
			(layers "F.Cu" "F.Mask" "F.Paste")
			(net "GND")
		)
		(pad "BP55" smd circle
			(at 15.830042 8.459978 180)
			(size 0.450088 0.450088)
			(layers "F.Cu" "F.Mask" "F.Paste")
			(net "Net_1807")
		)
		(pad "BP56" smd circle
			(at 16.770096 8.459978 180)
			(size 0.450088 0.450088)
			(layers "F.Cu" "F.Mask" "F.Paste")
			(net "M_C_CPU0_SB_RSP<0>")
		)
		(pad "BP57" smd circle
			(at 17.709896 8.459978 180)
			(size 0.450088 0.450088)
			(layers "F.Cu" "F.Mask" "F.Paste")
			(net "GND")
		)
		(pad "BP58" smd circle
			(at 18.64995 8.459978 180)
			(size 0.450088 0.450088)
			(layers "F.Cu" "F.Mask" "F.Paste")
			(net "Net_1815")
		)
		(pad "BP59" smd circle
			(at 19.590004 8.459978 180)
			(size 0.450088 0.450088)
			(layers "F.Cu" "F.Mask" "F.Paste")
			(net "GND")
		)
		(pad "BP60" smd circle
			(at 20.530058 8.459978 180)
			(size 0.450088 0.450088)
			(layers "F.Cu" "F.Mask" "F.Paste")
			(net "M_D_CPU0_SB_RSP<0>")
		)
		(pad "BP61" smd circle
			(at 21.470112 8.459978 180)
			(size 0.450088 0.450088)
			(layers "F.Cu" "F.Mask" "F.Paste")
			(net "GND")
		)
		(pad "BP62" smd circle
			(at 22.409912 8.459978 180)
			(size 0.450088 0.450088)
			(layers "F.Cu" "F.Mask" "F.Paste")
			(net "Net_1799")
		)
		(pad "BP63" smd circle
			(at 23.349966 8.459978 180)
			(size 0.450088 0.450088)
			(layers "F.Cu" "F.Mask" "F.Paste")
			(net "M_B_CPU0_SB_RSP<0>")
		)
		(pad "BP64" smd circle
			(at 24.29002 8.459978 180)
			(size 0.450088 0.450088)
			(layers "F.Cu" "F.Mask" "F.Paste")
			(net "GND")
		)
		(pad "BP65" smd circle
			(at 25.230074 8.459978 180)
			(size 0.450088 0.450088)
			(layers "F.Cu" "F.Mask" "F.Paste")
			(net "Net_1831")
		)
		(pad "BP66" smd circle
			(at 26.170128 8.459978 180)
			(size 0.450088 0.450088)
			(layers "F.Cu" "F.Mask" "F.Paste")
			(net "GND")
		)
		(pad "BP67" smd circle
			(at 27.109928 8.459978 180)
			(size 0.450088 0.450088)
			(layers "F.Cu" "F.Mask" "F.Paste")
			(net "M_F_CPU0_SB_RSP<0>")
		)
		(pad "BP68" smd circle
			(at 28.049982 8.459978 180)
			(size 0.450088 0.450088)
			(layers "F.Cu" "F.Mask" "F.Paste")
			(net "GND")
		)
		(pad "BP69" smd circle
			(at 28.990036 8.459978 180)
			(size 0.450088 0.450088)
			(layers "F.Cu" "F.Mask" "F.Paste")
			(net "Net_1823")
		)
		(pad "BP70" smd circle
			(at 29.93009 8.459978 180)
			(size 0.450088 0.450088)
			(layers "F.Cu" "F.Mask" "F.Paste")
			(net "M_E_CPU0_SB_RSP<0>")
		)
		(pad "BP71" smd circle
			(at 30.86989 8.459978 180)
			(size 0.450088 0.450088)
			(layers "F.Cu" "F.Mask" "F.Paste")
			(net "GND")
		)
		(pad "BP72" smd circle
			(at 31.809944 8.459978 180)
			(size 0.450088 0.450088)
			(layers "F.Cu" "F.Mask" "F.Paste")
			(net "Net_1791")
		)
		(pad "BP73" smd circle
			(at 32.749998 8.459978 180)
			(size 0.450088 0.450088)
			(layers "F.Cu" "F.Mask" "F.Paste")
			(net "GND")
		)
		(pad "BP74" smd circle
			(at 33.690052 8.459978 180)
			(size 0.450088 0.450088)
			(layers "F.Cu" "F.Mask" "F.Paste")
			(net "M_A_CPU0_SB_RSP<0>")
		)
		(pad "BR1" smd circle
			(at -34.459926 9.269984 180)
			(size 0.450088 0.450088)
			(layers "F.Cu" "F.Mask" "F.Paste")
			(net "GND")
		)
		(pad "BR2" smd circle
			(at -33.519872 9.269984 180)
			(size 0.450088 0.450088)
			(layers "F.Cu" "F.Mask" "F.Paste")
			(net "Net_1842")
		)
		(pad "BR3" smd circle
			(at -32.580072 9.269984 180)
			(size 0.450088 0.450088)
			(layers "F.Cu" "F.Mask" "F.Paste")
			(net "GND")
		)
		(pad "BR4" smd circle
			(at -31.640018 9.269984 180)
			(size 0.450088 0.450088)
			(layers "F.Cu" "F.Mask" "F.Paste")
			(net "PVDD11_S3_P0")
		)
		(pad "BR5" smd circle
			(at -30.699964 9.269984 180)
			(size 0.450088 0.450088)
			(layers "F.Cu" "F.Mask" "F.Paste")
			(net "Net_1971")
		)
		(pad "BR6" smd circle
			(at -29.75991 9.269984 180)
			(size 0.450088 0.450088)
			(layers "F.Cu" "F.Mask" "F.Paste")
			(net "GND")
		)
		(pad "BR7" smd circle
			(at -28.82011 9.269984 180)
			(size 0.450088 0.450088)
			(layers "F.Cu" "F.Mask" "F.Paste")
			(net "GND")
		)
		(pad "BR8" smd circle
			(at -27.880056 9.269984 180)
			(size 0.450088 0.450088)
			(layers "F.Cu" "F.Mask" "F.Paste")
			(net "GND")
		)
		(pad "BR9" smd circle
			(at -26.940002 9.269984 180)
			(size 0.450088 0.450088)
			(layers "F.Cu" "F.Mask" "F.Paste")
			(net "Net_1963")
		)
		(pad "BR10" smd circle
			(at -25.999948 9.269984 180)
			(size 0.450088 0.450088)
			(layers "F.Cu" "F.Mask" "F.Paste")
			(net "GND")
		)
		(pad "BR11" smd circle
			(at -25.059894 9.269984 180)
			(size 0.450088 0.450088)
			(layers "F.Cu" "F.Mask" "F.Paste")
			(net "PVDD11_S3_P0")
		)
		(pad "BR12" smd circle
			(at -24.120094 9.269984 180)
			(size 0.450088 0.450088)
			(layers "F.Cu" "F.Mask" "F.Paste")
			(net "Net_1850")
		)
		(pad "BR13" smd circle
			(at -23.18004 9.269984 180)
			(size 0.450088 0.450088)
			(layers "F.Cu" "F.Mask" "F.Paste")
			(net "GND")
		)
		(pad "BR14" smd circle
			(at -22.239986 9.269984 180)
			(size 0.450088 0.450088)
			(layers "F.Cu" "F.Mask" "F.Paste")
			(net "GND")
		)
		(pad "BR15" smd circle
			(at -21.299932 9.269984 180)
			(size 0.450088 0.450088)
			(layers "F.Cu" "F.Mask" "F.Paste")
			(net "GND")
		)
		(pad "BR16" smd circle
			(at -20.359878 9.269984 180)
			(size 0.450088 0.450088)
			(layers "F.Cu" "F.Mask" "F.Paste")
			(net "Net_1866")
		)
		(pad "BR17" smd circle
			(at -19.420078 9.269984 180)
			(size 0.450088 0.450088)
			(layers "F.Cu" "F.Mask" "F.Paste")
			(net "GND")
		)
		(pad "BR18" smd circle
			(at -18.480024 9.269984 180)
			(size 0.450088 0.450088)
			(layers "F.Cu" "F.Mask" "F.Paste")
			(net "PVDD11_S3_P0")
		)
		(pad "BR19" smd circle
			(at -17.53997 9.269984 180)
			(size 0.450088 0.450088)
			(layers "F.Cu" "F.Mask" "F.Paste")
			(net "Net_1858")
		)
		(pad "BR20" smd circle
			(at -16.599916 9.269984 180)
			(size 0.450088 0.450088)
			(layers "F.Cu" "F.Mask" "F.Paste")
			(net "GND")
		)
		(pad "BR21" smd circle
			(at -15.660116 9.269984 180)
			(size 0.450088 0.450088)
			(layers "F.Cu" "F.Mask" "F.Paste")
			(net "GND")
		)
		(pad "BR22" smd circle
			(at -14.720062 9.269984 180)
			(size 0.450088 0.450088)
			(layers "F.Cu" "F.Mask" "F.Paste")
			(net "GND")
		)
		(pad "BR23" smd circle
			(at -13.780008 9.269984 180)
			(size 0.450088 0.450088)
			(layers "F.Cu" "F.Mask" "F.Paste")
			(net "PVDDCR_CPU1_P0")
		)
		(pad "BR24" smd circle
			(at -12.839954 9.269984 180)
			(size 0.450088 0.450088)
			(layers "F.Cu" "F.Mask" "F.Paste")
			(net "GND")
		)
		(pad "BR25" smd circle
			(at -11.8999 9.269984 180)
			(size 0.450088 0.450088)
			(layers "F.Cu" "F.Mask" "F.Paste")
			(net "PVDDCR_CPU1_P0")
		)
		(pad "BR26" smd circle
			(at -10.9601 9.269984 180)
			(size 0.450088 0.450088)
			(layers "F.Cu" "F.Mask" "F.Paste")
			(net "GND")
		)
		(pad "BR27" smd circle
			(at -10.020046 9.269984 180)
			(size 0.450088 0.450088)
			(layers "F.Cu" "F.Mask" "F.Paste")
			(net "PVDDCR_CPU1_P0")
		)
	)
)
